# S9S_MB_2U (Grand Teton) — schematic netlist excerpt (pin names and nets, part order shuffled) for the footprints in the layout excerpt that follows; sources: Cadence DE-HDL packaged netlist, KiCad conversion of 03242023_DA0F0TMBIJ0_F0T_Motherboard_J_brd_V01_OCP.brd

C2276  Q_CAP  0.1UF 25V 10% X7R  pkg 0402  page 170 : A = P3V3_AUX ; B = GND
PC2147  Q_CAP  1UF 25V 10% X6S  pkg C0402  page 162 : A = GND ; B = P3V3_OCP_REG_2

(kicad_pcb
	(version 20260206)
	(generator "pcbnew")
	(generator_version "10.0")
	(general
		(thickness 1.6)
		(legacy_teardrops no)
	)
	(paper "A4")
	(title_block
		(title "03242023_DA0F0TMBIJ0_F0T_Motherboard_J_brd_V01_OCP.brd")
		(comment 1 "Grand Teton / footprints 1031-1032 of 6105")
	)
	(layers
		(0 "F.Cu" signal "TOP")
		(4 "In1.Cu" signal "GND")
		(6 "In2.Cu" signal "IN1")
		(8 "In3.Cu" signal "GND1")
		(10 "In4.Cu" signal "IN2")
		(12 "In5.Cu" signal "GND2")
		(14 "In6.Cu" signal "IN3")
		(16 "In7.Cu" signal "GND3")
		(18 "In8.Cu" signal "VCC")
		(20 "In9.Cu" signal "VCC1")
		(22 "In10.Cu" signal "GND4")
		(24 "In11.Cu" signal "IN4")
		(26 "In12.Cu" signal "GND5")
		(28 "In13.Cu" signal "IN5")
		(30 "In14.Cu" signal "GND6")
		(32 "In15.Cu" signal "IN6")
		(34 "In16.Cu" signal "GND7")
		(2 "B.Cu" signal "BOTTOM")
		(9 "F.Adhes" user "F.Adhesive")
		(11 "B.Adhes" user "B.Adhesive")
		(13 "F.Paste" user "Package Geometry/Pastemask Top")
		(15 "B.Paste" user "Package Geometry/Pastemask Bottom")
		(5 "F.SilkS" user "Ref Des/Silkscreen Top")
		(7 "B.SilkS" user "Ref Des/Silkscreen Bottom")
		(1 "F.Mask" user "Board Geometry/Soldermask Top")
		(3 "B.Mask" user "Board Geometry/Soldermask Bottom")
		(17 "Dwgs.User" user "User.Drawings")
		(19 "Cmts.User" user "User.Comments")
		(21 "Eco1.User" user "User.Eco1")
		(23 "Eco2.User" user "User.Eco2")
		(25 "Edge.Cuts" user "Board Geometry/Outline")
		(27 "Margin" user)
		(31 "F.CrtYd" user "Package Geometry/Place Bound Top")
		(29 "B.CrtYd" user "Package Geometry/Place Bound Bottom")
		(35 "F.Fab" user "Ref Des/Assembly Top")
		(33 "B.Fab" user "Ref Des/Assembly Bottom")
	)
	(footprint ""
		(layer "F.Cu")
		(at 81.82737 -59.364626 -90)
		(property "Reference" "PC2147"
			(at 0 0 270)
			(layer "F.SilkS")
			(hide yes)
			(effects
				(font
					(size 1.27 1.27)
				)
			)
		)
		(property "Value" ""
			(at 0 0 270)
			(layer "F.Fab")
			(effects
				(font
					(size 1.27 1.27)
				)
			)
		)
		(duplicate_pad_numbers_are_jumpers no)
		(fp_line
			(start -0.7874 0.4064)
			(end -0.7874 -0.4064)
			(stroke
				(width 0.1524)
				(type default)
			)
			(layer "F.SilkS")
		)
		(fp_line
			(start 0.7874 0.4064)
			(end -0.7874 0.4064)
			(stroke
				(width 0.1524)
				(type default)
			)
			(layer "F.SilkS")
		)
		(fp_line
			(start -0.7874 -0.4064)
			(end 0.7874 -0.4064)
			(stroke
				(width 0.1524)
				(type default)
			)
			(layer "F.SilkS")
		)
		(fp_line
			(start 0.7874 -0.4064)
			(end 0.7874 0.4064)
			(stroke
				(width 0.1524)
				(type default)
			)
			(layer "F.SilkS")
		)
		(fp_line
			(start -0.67945 0.3048)
			(end -0.67945 -0.305054)
			(stroke
				(width 0.1)
				(type default)
			)
			(layer "F.Fab")
		)
		(fp_line
			(start -0.12065 0.3048)
			(end -0.67945 0.3048)
			(stroke
				(width 0.1)
				(type default)
			)
			(layer "F.Fab")
		)
		(fp_line
			(start 0.120396 0.3048)
			(end 0.120396 0.2794)
			(stroke
				(width 0.1)
				(type default)
			)
			(layer "F.Fab")
		)
		(fp_line
			(start 0.67945 0.3048)
			(end 0.120396 0.3048)
			(stroke
				(width 0.1)
				(type default)
			)
			(layer "F.Fab")
		)
		(fp_line
			(start -0.12065 0.2794)
			(end -0.12065 0.3048)
			(stroke
				(width 0.1)
				(type default)
			)
			(layer "F.Fab")
		)
		(fp_line
			(start 0.120396 0.2794)
			(end -0.12065 0.2794)
			(stroke
				(width 0.1)
				(type default)
			)
			(layer "F.Fab")
		)
		(fp_line
			(start -0.12065 -0.2794)
			(end 0.12065 -0.2794)
			(stroke
				(width 0.1)
				(type default)
			)
			(layer "F.Fab")
		)
		(fp_line
			(start 0.12065 -0.2794)
			(end 0.12065 -0.3048)
			(stroke
				(width 0.1)
				(type default)
			)
			(layer "F.Fab")
		)
		(fp_line
			(start 0.12065 -0.3048)
			(end 0.67945 -0.3048)
			(stroke
				(width 0.1)
				(type default)
			)
			(layer "F.Fab")
		)
		(fp_line
			(start 0.67945 -0.3048)
			(end 0.67945 0.3048)
			(stroke
				(width 0.1)
				(type default)
			)
			(layer "F.Fab")
		)
		(fp_line
			(start -0.67945 -0.305054)
			(end -0.12065 -0.305054)
			(stroke
				(width 0.1)
				(type default)
			)
			(layer "F.Fab")
		)
		(fp_line
			(start -0.12065 -0.305054)
			(end -0.12065 -0.2794)
			(stroke
				(width 0.1)
				(type default)
			)
			(layer "F.Fab")
		)
		(pad "1" smd circle
			(at -0.40005 0 270)
			(size 0 0)
			(layers "F.Cu" "F.Mask" "F.Paste")
			(net "GND")
		)
		(pad "2" smd circle
			(at 0.40005 0 270)
			(size 0 0)
			(layers "F.Cu" "F.Mask" "F.Paste")
			(net "P3V3_OCP_REG_2")
		)
	)
	(footprint ""
		(layer "F.Cu")
		(at 292.236398 -18.714466 180)
		(property "Reference" "C2276"
			(at 0 0 180)
			(layer "F.SilkS")
			(hide yes)
			(effects
				(font
					(size 1.27 1.27)
				)
			)
		)
		(property "Value" ""
			(at 0 0 180)
			(layer "F.Fab")
			(effects
				(font
					(size 1.27 1.27)
				)
			)
		)
		(duplicate_pad_numbers_are_jumpers no)
		(fp_line
			(start 0.7874 0.4064)
			(end -0.7874 0.4064)
			(stroke
				(width 0.1524)
				(type default)
			)
			(layer "F.SilkS")
		)
		(fp_line
			(start 0.7874 -0.4064)
			(end 0.7874 0.4064)
			(stroke
				(width 0.1524)
				(type default)
			)
			(layer "F.SilkS")
		)
		(fp_line
			(start -0.7874 0.4064)
			(end -0.7874 -0.4064)
			(stroke
				(width 0.1524)
				(type default)
			)
			(layer "F.SilkS")
		)
		(fp_line
			(start -0.7874 -0.4064)
			(end 0.7874 -0.4064)
			(stroke
				(width 0.1524)
				(type default)
			)
			(layer "F.SilkS")
		)
		(fp_line
			(start 0.67945 0.3048)
			(end 0.120396 0.3048)
			(stroke
				(width 0.1)
				(type default)
			)
			(layer "F.Fab")
		)
		(fp_line
			(start 0.67945 -0.3048)
			(end 0.67945 0.3048)
			(stroke
				(width 0.1)
				(type default)
			)
			(layer "F.Fab")
		)
		(fp_line
			(start 0.12065 -0.2794)
			(end 0.12065 -0.3048)
			(stroke
				(width 0.1)
				(type default)
			)
			(layer "F.Fab")
		)
		(fp_line
			(start 0.12065 -0.3048)
			(end 0.67945 -0.3048)
			(stroke
				(width 0.1)
				(type default)
			)
			(layer "F.Fab")
		)
		(fp_line
			(start 0.120396 0.3048)
			(end 0.120396 0.2794)
			(stroke
				(width 0.1)
				(type default)
			)
			(layer "F.Fab")
		)
		(fp_line
			(start 0.120396 0.2794)
			(end -0.12065 0.2794)
			(stroke
				(width 0.1)
				(type default)
			)
			(layer "F.Fab")
		)
		(fp_line
			(start -0.12065 0.3048)
			(end -0.67945 0.3048)
			(stroke
				(width 0.1)
				(type default)
			)
			(layer "F.Fab")
		)
		(fp_line
			(start -0.12065 0.2794)
			(end -0.12065 0.3048)
			(stroke
				(width 0.1)
				(type default)
			)
			(layer "F.Fab")
		)
		(fp_line
			(start -0.12065 -0.2794)
			(end 0.12065 -0.2794)
			(stroke
				(width 0.1)
				(type default)
			)
			(layer "F.Fab")
		)
		(fp_line
			(start -0.12065 -0.305054)
			(end -0.12065 -0.2794)
			(stroke
				(width 0.1)
				(type default)
			)
			(layer "F.Fab")
		)
		(fp_line
			(start -0.67945 0.3048)
			(end -0.67945 -0.305054)
			(stroke
				(width 0.1)
				(type default)
			)
			(layer "F.Fab")
		)
		(fp_line
			(start -0.67945 -0.305054)
			(end -0.12065 -0.305054)
			(stroke
				(width 0.1)
				(type default)
			)
			(layer "F.Fab")
		)
		(pad "1" smd circle
			(at -0.40005 0 180)
			(size 0 0)
			(layers "F.Cu" "F.Mask" "F.Paste")
			(net "P3V3_AUX")
		)
		(pad "2" smd circle
			(at 0.40005 0 180)
			(size 0 0)
			(layers "F.Cu" "F.Mask" "F.Paste")
			(net "GND")
		)
	)
)
